(kicad_pcb
	(version 20260206)
	(generator "pcbnew")
	(generator_version "10.0")
	(general
		(thickness 1.6)
		(legacy_teardrops no)
	)
	(paper "A4")
	(title_block
		(title "01162023_DA0F0TEBIF0_F0T_Expander_BD_F_brd_V02_OCP.brd")
		(comment 1 "Grand Teton / footprints 6825-6831 of 9728")
	)
	(layers
		(0 "F.Cu" signal "TOP")
		(4 "In1.Cu" signal "GND")
		(6 "In2.Cu" signal "VCC")
		(8 "In3.Cu" signal "VCC1")
		(10 "In4.Cu" signal "GND1")
		(12 "In5.Cu" signal "IN1")
		(14 "In6.Cu" signal "GND2")
		(16 "In7.Cu" signal "IN2")
		(18 "In8.Cu" signal "GND3")
		(20 "In9.Cu" signal "IN3")
		(22 "In10.Cu" signal "GND4")
		(24 "In11.Cu" signal "IN4")
		(26 "In12.Cu" signal "GND5")
		(28 "In13.Cu" signal "IN5")
		(30 "In14.Cu" signal "GND6")
		(32 "In15.Cu" signal "IN6")
		(34 "In16.Cu" signal "GND7")
		(2 "B.Cu" signal "BOTTOM")
		(9 "F.Adhes" user "F.Adhesive")
		(11 "B.Adhes" user "B.Adhesive")
		(13 "F.Paste" user "Package Geometry/Pastemask Top")
		(15 "B.Paste" user "Package Geometry/Pastemask Bottom")
		(5 "F.SilkS" user "Ref Des/Silkscreen Top")
		(7 "B.SilkS" user "Ref Des/Silkscreen Bottom")
		(1 "F.Mask" user "Board Geometry/Soldermask Top")
		(3 "B.Mask" user "Board Geometry/Soldermask Bottom")
		(17 "Dwgs.User" user "User.Drawings")
		(19 "Cmts.User" user "User.Comments")
		(21 "Eco1.User" user "User.Eco1")
		(23 "Eco2.User" user "User.Eco2")
		(25 "Edge.Cuts" user "Board Geometry/Outline")
		(27 "Margin" user)
		(31 "F.CrtYd" user "Package Geometry/Place Bound Top")
		(29 "B.CrtYd" user "Package Geometry/Place Bound Bottom")
		(35 "F.Fab" user "Ref Des/Assembly Top")
		(33 "B.Fab" user "Ref Des/Assembly Bottom")
	)
	(footprint ""
		(layer "F.Cu")
		(at 7.771892 -24.807418)
		(property "Reference" "R410"
			(at 0 0 0)
			(layer "F.SilkS")
			(hide yes)
			(effects
				(font
					(size 1.27 1.27)
				)
			)
		)
		(property "Value" ""
			(at 0 0 0)
			(layer "F.Fab")
			(effects
				(font
					(size 1.27 1.27)
				)
			)
		)
		(duplicate_pad_numbers_are_jumpers no)
		(fp_line
			(start -0.7874 -0.4064)
			(end 0.7874 -0.4064)
			(stroke
				(width 0.1524)
				(type default)
			)
			(layer "F.SilkS")
		)
		(fp_line
			(start -0.7874 0.4064)
			(end -0.7874 -0.4064)
			(stroke
				(width 0.1524)
				(type default)
			)
			(layer "F.SilkS")
		)
		(fp_line
			(start 0.7874 -0.4064)
			(end 0.7874 0.4064)
			(stroke
				(width 0.1524)
				(type default)
			)
			(layer "F.SilkS")
		)
		(fp_line
			(start 0.7874 0.4064)
			(end -0.7874 0.4064)
			(stroke
				(width 0.1524)
				(type default)
			)
			(layer "F.SilkS")
		)
		(fp_line
			(start -0.67945 -0.305054)
			(end -0.12065 -0.305054)
			(stroke
				(width 0.1)
				(type default)
			)
			(layer "F.Fab")
		)
		(fp_line
			(start -0.67945 0.3048)
			(end -0.67945 -0.305054)
			(stroke
				(width 0.1)
				(type default)
			)
			(layer "F.Fab")
		)
		(fp_line
			(start -0.12065 -0.305054)
			(end -0.12065 -0.2794)
			(stroke
				(width 0.1)
				(type default)
			)
			(layer "F.Fab")
		)
		(fp_line
			(start -0.12065 -0.2794)
			(end 0.12065 -0.2794)
			(stroke
				(width 0.1)
				(type default)
			)
			(layer "F.Fab")
		)
		(fp_line
			(start -0.12065 0.2794)
			(end -0.12065 0.3048)
			(stroke
				(width 0.1)
				(type default)
			)
			(layer "F.Fab")
		)
		(fp_line
			(start -0.12065 0.3048)
			(end -0.67945 0.3048)
			(stroke
				(width 0.1)
				(type default)
			)
			(layer "F.Fab")
		)
		(fp_line
			(start 0.120396 0.2794)
			(end -0.12065 0.2794)
			(stroke
				(width 0.1)
				(type default)
			)
			(layer "F.Fab")
		)
		(fp_line
			(start 0.120396 0.3048)
			(end 0.120396 0.2794)
			(stroke
				(width 0.1)
				(type default)
			)
			(layer "F.Fab")
		)
		(fp_line
			(start 0.12065 -0.3048)
			(end 0.67945 -0.3048)
			(stroke
				(width 0.1)
				(type default)
			)
			(layer "F.Fab")
		)
		(fp_line
			(start 0.12065 -0.2794)
			(end 0.12065 -0.3048)
			(stroke
				(width 0.1)
				(type default)
			)
			(layer "F.Fab")
		)
		(fp_line
			(start 0.67945 -0.3048)
			(end 0.67945 0.3048)
			(stroke
				(width 0.1)
				(type default)
			)
			(layer "F.Fab")
		)
		(fp_line
			(start 0.67945 0.3048)
			(end 0.120396 0.3048)
			(stroke
				(width 0.1)
				(type default)
			)
			(layer "F.Fab")
		)
		(pad "1" smd circle
			(at -0.40005 0)
			(size 0 0)
			(layers "F.Cu" "F.Mask" "F.Paste")
			(net "P3V3_SSD0")
		)
		(pad "2" smd circle
			(at 0.40005 0)
			(size 0 0)
			(layers "F.Cu" "F.Mask" "F.Paste")
			(net "PU_CLKREQ0")
		)
	)
	(footprint ""
		(layer "F.Cu")
		(at 30.153356 -297.791632)
		(property "Reference" "L88"
			(at 0 0 0)
			(layer "F.SilkS")
			(hide yes)
			(effects
				(font
					(size 1.27 1.27)
				)
			)
		)
		(property "Value" ""
			(at 0 0 0)
			(layer "F.Fab")
			(effects
				(font
					(size 1.27 1.27)
				)
			)
		)
		(duplicate_pad_numbers_are_jumpers no)
		(fp_line
			(start -1.63576 -0.8128)
			(end -1.63576 0.8128)
			(stroke
				(width 0.1524)
				(type default)
			)
			(layer "F.SilkS")
		)
		(fp_line
			(start -1.63576 -0.8128)
			(end 1.63576 -0.8128)
			(stroke
				(width 0.1524)
				(type default)
			)
			(layer "F.SilkS")
		)
		(fp_line
			(start 1.63576 -0.8128)
			(end 1.63576 0.8128)
			(stroke
				(width 0.1524)
				(type default)
			)
			(layer "F.SilkS")
		)
		(fp_line
			(start 1.63576 0.8128)
			(end -1.63576 0.8128)
			(stroke
				(width 0.1524)
				(type default)
			)
			(layer "F.SilkS")
		)
		(fp_line
			(start -1.56083 -0.738632)
			(end -1.56083 0.7366)
			(stroke
				(width 0.1)
				(type default)
			)
			(layer "F.Fab")
		)
		(fp_line
			(start -1.56083 0.7366)
			(end -1.524 0.7366)
			(stroke
				(width 0.1)
				(type default)
			)
			(layer "F.Fab")
		)
		(fp_line
			(start -1.524 0.7366)
			(end 1.524 0.7366)
			(stroke
				(width 0.1)
				(type default)
			)
			(layer "F.Fab")
		)
		(fp_line
			(start 1.524 0.7366)
			(end 1.560576 0.7366)
			(stroke
				(width 0.1)
				(type default)
			)
			(layer "F.Fab")
		)
		(fp_line
			(start 1.560576 -0.738632)
			(end -1.56083 -0.738632)
			(stroke
				(width 0.1)
				(type default)
			)
			(layer "F.Fab")
		)
		(fp_line
			(start 1.560576 0.7366)
			(end 1.560576 -0.738632)
			(stroke
				(width 0.1)
				(type default)
			)
			(layer "F.Fab")
		)
		(pad "1" smd rect
			(at -0.94996 0 180)
			(size 1.1176 1.3716)
			(layers "F.Cu" "F.Mask" "F.Paste")
			(net "P1V8_PLL0_PEX0")
		)
		(pad "2" smd rect
			(at 0.94996 0 180)
			(size 1.1176 1.3716)
			(layers "F.Cu" "F.Mask" "F.Paste")
			(net "PCEPLL0_VDDA18_PEX0")
		)
	)
	(footprint ""
		(layer "F.Cu")
		(at 227.562664 -207.02016 -90)
		(property "Reference" "R5292"
			(at 0 0 270)
			(layer "F.SilkS")
			(hide yes)
			(effects
				(font
					(size 1.27 1.27)
				)
			)
		)
		(property "Value" ""
			(at 0 0 270)
			(layer "F.Fab")
			(effects
				(font
					(size 1.27 1.27)
				)
			)
		)
		(duplicate_pad_numbers_are_jumpers no)
		(fp_line
			(start -0.7874 0.4064)
			(end -0.7874 -0.4064)
			(stroke
				(width 0.1524)
				(type default)
			)
			(layer "F.SilkS")
		)
		(fp_line
			(start 0.7874 0.4064)
			(end -0.7874 0.4064)
			(stroke
				(width 0.1524)
				(type default)
			)
			(layer "F.SilkS")
		)
		(fp_line
			(start -0.7874 -0.4064)
			(end 0.7874 -0.4064)
			(stroke
				(width 0.1524)
				(type default)
			)
			(layer "F.SilkS")
		)
		(fp_line
			(start 0.7874 -0.4064)
			(end 0.7874 0.4064)
			(stroke
				(width 0.1524)
				(type default)
			)
			(layer "F.SilkS")
		)
		(fp_line
			(start -0.67945 0.3048)
			(end -0.67945 -0.305054)
			(stroke
				(width 0.1)
				(type default)
			)
			(layer "F.Fab")
		)
		(fp_line
			(start -0.12065 0.3048)
			(end -0.67945 0.3048)
			(stroke
				(width 0.1)
				(type default)
			)
			(layer "F.Fab")
		)
		(fp_line
			(start 0.120396 0.3048)
			(end 0.120396 0.2794)
			(stroke
				(width 0.1)
				(type default)
			)
			(layer "F.Fab")
		)
		(fp_line
			(start 0.67945 0.3048)
			(end 0.120396 0.3048)
			(stroke
				(width 0.1)
				(type default)
			)
			(layer "F.Fab")
		)
		(fp_line
			(start -0.12065 0.2794)
			(end -0.12065 0.3048)
			(stroke
				(width 0.1)
				(type default)
			)
			(layer "F.Fab")
		)
		(fp_line
			(start 0.120396 0.2794)
			(end -0.12065 0.2794)
			(stroke
				(width 0.1)
				(type default)
			)
			(layer "F.Fab")
		)
		(fp_line
			(start -0.12065 -0.2794)
			(end 0.12065 -0.2794)
			(stroke
				(width 0.1)
				(type default)
			)
			(layer "F.Fab")
		)
		(fp_line
			(start 0.12065 -0.2794)
			(end 0.12065 -0.3048)
			(stroke
				(width 0.1)
				(type default)
			)
			(layer "F.Fab")
		)
		(fp_line
			(start 0.12065 -0.3048)
			(end 0.67945 -0.3048)
			(stroke
				(width 0.1)
				(type default)
			)
			(layer "F.Fab")
		)
		(fp_line
			(start 0.67945 -0.3048)
			(end 0.67945 0.3048)
			(stroke
				(width 0.1)
				(type default)
			)
			(layer "F.Fab")
		)
		(fp_line
			(start -0.67945 -0.305054)
			(end -0.12065 -0.305054)
			(stroke
				(width 0.1)
				(type default)
			)
			(layer "F.Fab")
		)
		(fp_line
			(start -0.12065 -0.305054)
			(end -0.12065 -0.2794)
			(stroke
				(width 0.1)
				(type default)
			)
			(layer "F.Fab")
		)
		(pad "1" smd circle
			(at -0.40005 0 270)
			(size 0 0)
			(layers "F.Cu" "F.Mask" "F.Paste")
			(net "BIC_SYS_READY_N")
		)
		(pad "2" smd circle
			(at 0.40005 0 270)
			(size 0 0)
			(layers "F.Cu" "F.Mask" "F.Paste")
			(net "BIC_SYS_READY_R_N")
		)
	)
	(footprint ""
		(layer "F.Cu")
		(at 311.662318 -22.937216 90)
		(property "Reference" "R1711"
			(at 0 0 90)
			(layer "F.SilkS")
			(hide yes)
			(effects
				(font
					(size 1.27 1.27)
				)
			)
		)
		(property "Value" ""
			(at 0 0 90)
			(layer "F.Fab")
			(effects
				(font
					(size 1.27 1.27)
				)
			)
		)
		(duplicate_pad_numbers_are_jumpers no)
		(fp_line
			(start 0.7874 -0.4064)
			(end 0.7874 0.4064)
			(stroke
				(width 0.1524)
				(type default)
			)
			(layer "F.SilkS")
		)
		(fp_line
			(start -0.7874 -0.4064)
			(end 0.7874 -0.4064)
			(stroke
				(width 0.1524)
				(type default)
			)
			(layer "F.SilkS")
		)
		(fp_line
			(start 0.7874 0.4064)
			(end -0.7874 0.4064)
			(stroke
				(width 0.1524)
				(type default)
			)
			(layer "F.SilkS")
		)
		(fp_line
			(start -0.7874 0.4064)
			(end -0.7874 -0.4064)
			(stroke
				(width 0.1524)
				(type default)
			)
			(layer "F.SilkS")
		)
		(fp_line
			(start -0.12065 -0.305054)
			(end -0.12065 -0.2794)
			(stroke
				(width 0.1)
				(type default)
			)
			(layer "F.Fab")
		)
		(fp_line
			(start -0.67945 -0.305054)
			(end -0.12065 -0.305054)
			(stroke
				(width 0.1)
				(type default)
			)
			(layer "F.Fab")
		)
		(fp_line
			(start 0.67945 -0.3048)
			(end 0.67945 0.3048)
			(stroke
				(width 0.1)
				(type default)
			)
			(layer "F.Fab")
		)
		(fp_line
			(start 0.12065 -0.3048)
			(end 0.67945 -0.3048)
			(stroke
				(width 0.1)
				(type default)
			)
			(layer "F.Fab")
		)
		(fp_line
			(start 0.12065 -0.2794)
			(end 0.12065 -0.3048)
			(stroke
				(width 0.1)
				(type default)
			)
			(layer "F.Fab")
		)
		(fp_line
			(start -0.12065 -0.2794)
			(end 0.12065 -0.2794)
			(stroke
				(width 0.1)
				(type default)
			)
			(layer "F.Fab")
		)
		(fp_line
			(start 0.120396 0.2794)
			(end -0.12065 0.2794)
			(stroke
				(width 0.1)
				(type default)
			)
			(layer "F.Fab")
		)
		(fp_line
			(start -0.12065 0.2794)
			(end -0.12065 0.3048)
			(stroke
				(width 0.1)
				(type default)
			)
			(layer "F.Fab")
		)
		(fp_line
			(start 0.67945 0.3048)
			(end 0.120396 0.3048)
			(stroke
				(width 0.1)
				(type default)
			)
			(layer "F.Fab")
		)
		(fp_line
			(start 0.120396 0.3048)
			(end 0.120396 0.2794)
			(stroke
				(width 0.1)
				(type default)
			)
			(layer "F.Fab")
		)
		(fp_line
			(start -0.12065 0.3048)
			(end -0.67945 0.3048)
			(stroke
				(width 0.1)
				(type default)
			)
			(layer "F.Fab")
		)
		(fp_line
			(start -0.67945 0.3048)
			(end -0.67945 -0.305054)
			(stroke
				(width 0.1)
				(type default)
			)
			(layer "F.Fab")
		)
		(pad "1" smd circle
			(at -0.40005 0 90)
			(size 0 0)
			(layers "F.Cu" "F.Mask" "F.Paste")
			(net "SMB_BIC_I2C9_MUX1_SSD10_R_SDA")
		)
		(pad "2" smd circle
			(at 0.40005 0 90)
			(size 0 0)
			(layers "F.Cu" "F.Mask" "F.Paste")
			(net "SMB_ISO_SSD10_SDA")
		)
	)
	(footprint ""
		(layer "F.Cu")
		(at 127.381508 -356.244906 90)
		(property "Reference" "C2273"
			(at 0 0 90)
			(layer "F.SilkS")
			(hide yes)
			(effects
				(font
					(size 1.27 1.27)
				)
			)
		)
		(property "Value" ""
			(at 0 0 90)
			(layer "F.Fab")
			(effects
				(font
					(size 1.27 1.27)
				)
			)
		)
		(duplicate_pad_numbers_are_jumpers no)
		(fp_line
			(start 0.299974 -0.150114)
			(end 0.299974 0.150114)
			(stroke
				(width 0.1)
				(type default)
			)
			(layer "F.Fab")
		)
		(fp_line
			(start -0.299974 -0.150114)
			(end 0.299974 -0.150114)
			(stroke
				(width 0.1)
				(type default)
			)
			(layer "F.Fab")
		)
		(fp_line
			(start 0.299974 0.150114)
			(end -0.299974 0.150114)
			(stroke
				(width 0.1)
				(type default)
			)
			(layer "F.Fab")
		)
		(fp_line
			(start -0.299974 0.150114)
			(end -0.299974 -0.150114)
			(stroke
				(width 0.1)
				(type default)
			)
			(layer "F.Fab")
		)
		(pad "1" smd rect
			(at -0.2667 0 90)
			(size 0.3048 0.381)
			(layers "F.Cu" "F.Mask" "F.Paste")
			(net "P5E_PEX1_STN5_TX_DP<80>")
		)
		(pad "2" smd rect
			(at 0.2667 0 90)
			(size 0.3048 0.381)
			(layers "F.Cu" "F.Mask" "F.Paste")
			(net "P5E_PEX1_STN5_TX_C_DP<80>")
		)
	)
	(footprint ""
		(layer "F.Cu")
		(at 198.76135 -147.99691 180)
		(property "Reference" "C221"
			(at 0 0 180)
			(layer "F.SilkS")
			(hide yes)
			(effects
				(font
					(size 1.27 1.27)
				)
			)
		)
		(property "Value" ""
			(at 0 0 180)
			(layer "F.Fab")
			(effects
				(font
					(size 1.27 1.27)
				)
			)
		)
		(duplicate_pad_numbers_are_jumpers no)
		(fp_line
			(start 0.299974 0.150114)
			(end -0.299974 0.150114)
			(stroke
				(width 0.1)
				(type default)
			)
			(layer "F.Fab")
		)
		(fp_line
			(start 0.299974 -0.150114)
			(end 0.299974 0.150114)
			(stroke
				(width 0.1)
				(type default)
			)
			(layer "F.Fab")
		)
		(fp_line
			(start -0.299974 0.150114)
			(end -0.299974 -0.150114)
			(stroke
				(width 0.1)
				(type default)
			)
			(layer "F.Fab")
		)
		(fp_line
			(start -0.299974 -0.150114)
			(end 0.299974 -0.150114)
			(stroke
				(width 0.1)
				(type default)
			)
			(layer "F.Fab")
		)
		(pad "1" smd rect
			(at -0.2667 0 180)
			(size 0.3048 0.381)
			(layers "F.Cu" "F.Mask" "F.Paste")
			(net "P5E_PEX1_STN0_TX_DN<11>")
		)
		(pad "2" smd rect
			(at 0.2667 0 180)
			(size 0.3048 0.381)
			(layers "F.Cu" "F.Mask" "F.Paste")
			(net "P5E_PEX1_STN0_TX_C_DN<11>")
		)
	)
	(footprint ""
		(layer "F.Cu")
		(at 292.73119 -195.362068 90)
		(property "Reference" "R3369"
			(at 0 0 90)
			(layer "F.SilkS")
			(hide yes)
			(effects
				(font
					(size 1.27 1.27)
				)
			)
		)
		(property "Value" ""
			(at 0 0 90)
			(layer "F.Fab")
			(effects
				(font
					(size 1.27 1.27)
				)
			)
		)
		(duplicate_pad_numbers_are_jumpers no)
		(fp_line
			(start 0.7874 -0.4064)
			(end 0.7874 0.4064)
			(stroke
				(width 0.1524)
				(type default)
			)
			(layer "F.SilkS")
		)
		(fp_line
			(start -0.7874 -0.4064)
			(end 0.7874 -0.4064)
			(stroke
				(width 0.1524)
				(type default)
			)
			(layer "F.SilkS")
		)
		(fp_line
			(start 0.7874 0.4064)
			(end -0.7874 0.4064)
			(stroke
				(width 0.1524)
				(type default)
			)
			(layer "F.SilkS")
		)
		(fp_line
			(start -0.7874 0.4064)
			(end -0.7874 -0.4064)
			(stroke
				(width 0.1524)
				(type default)
			)
			(layer "F.SilkS")
		)
		(fp_line
			(start -0.12065 -0.305054)
			(end -0.12065 -0.2794)
			(stroke
				(width 0.1)
				(type default)
			)
			(layer "F.Fab")
		)
		(fp_line
			(start -0.67945 -0.305054)
			(end -0.12065 -0.305054)
			(stroke
				(width 0.1)
				(type default)
			)
			(layer "F.Fab")
		)
		(fp_line
			(start 0.67945 -0.3048)
			(end 0.67945 0.3048)
			(stroke
				(width 0.1)
				(type default)
			)
			(layer "F.Fab")
		)
		(fp_line
			(start 0.12065 -0.3048)
			(end 0.67945 -0.3048)
			(stroke
				(width 0.1)
				(type default)
			)
			(layer "F.Fab")
		)
		(fp_line
			(start 0.12065 -0.2794)
			(end 0.12065 -0.3048)
			(stroke
				(width 0.1)
				(type default)
			)
			(layer "F.Fab")
		)
		(fp_line
			(start -0.12065 -0.2794)
			(end 0.12065 -0.2794)
			(stroke
				(width 0.1)
				(type default)
			)
			(layer "F.Fab")
		)
		(fp_line
			(start 0.120396 0.2794)
			(end -0.12065 0.2794)
			(stroke
				(width 0.1)
				(type default)
			)
			(layer "F.Fab")
		)
		(fp_line
			(start -0.12065 0.2794)
			(end -0.12065 0.3048)
			(stroke
				(width 0.1)
				(type default)
			)
			(layer "F.Fab")
		)
		(fp_line
			(start 0.67945 0.3048)
			(end 0.120396 0.3048)
			(stroke
				(width 0.1)
				(type default)
			)
			(layer "F.Fab")
		)
		(fp_line
			(start 0.120396 0.3048)
			(end 0.120396 0.2794)
			(stroke
				(width 0.1)
				(type default)
			)
			(layer "F.Fab")
		)
		(fp_line
			(start -0.12065 0.3048)
			(end -0.67945 0.3048)
			(stroke
				(width 0.1)
				(type default)
			)
			(layer "F.Fab")
		)
		(fp_line
			(start -0.67945 0.3048)
			(end -0.67945 -0.305054)
			(stroke
				(width 0.1)
				(type default)
			)
			(layer "F.Fab")
		)
		(pad "1" smd circle
			(at -0.40005 0 90)
			(size 0 0)
			(layers "F.Cu" "F.Mask" "F.Paste")
			(net "SPI_BIC1_LS23_EN_N")
		)
		(pad "2" smd circle
			(at 0.40005 0 90)
			(size 0 0)
			(layers "F.Cu" "F.Mask" "F.Paste")
			(net "SPI_BIC1_LS23_EN_R_N")
		)
	)
)
